# T6G (Grand Teton) — schematic netlist excerpt (pin names and nets, part order shuffled) for the footprints in the layout excerpt that follows; sources: Cadence DE-HDL packaged netlist, KiCad conversion of 04192023_DAF0TMB3IC0_F0TG_MB_C_brd_V02_OCP.brd

R4121  Q_RES  10K 1% CHIP  pkg 0402LF  page 125 : A = P3V3_AUX ; B = PRSNT_CABLE_GPU_B3_N
C67  Q_CAP  0.1UF 25V 10% EMPTY  pkg 0402  page 240 : A = FM_GPU_HSC_EN_BUF_R1 ; B = GND

(kicad_pcb
	(version 20260206)
	(generator "pcbnew")
	(generator_version "10.0")
	(general
		(thickness 1.6)
		(legacy_teardrops no)
	)
	(paper "A4")
	(title_block
		(title "04192023_DAF0TMB3IC0_F0TG_MB_C_brd_V02_OCP.brd")
		(comment 1 "Grand Teton / footprints 6614-6615 of 8354")
	)
	(layers
		(0 "F.Cu" signal "TOP")
		(4 "In1.Cu" signal "GND")
		(6 "In2.Cu" signal "IN1")
		(8 "In3.Cu" signal "GND1")
		(10 "In4.Cu" signal "IN2")
		(12 "In5.Cu" signal "GND2")
		(14 "In6.Cu" signal "IN3")
		(16 "In7.Cu" signal "GND3")
		(18 "In8.Cu" signal "VCC")
		(20 "In9.Cu" signal "VCC1")
		(22 "In10.Cu" signal "GND4")
		(24 "In11.Cu" signal "IN4")
		(26 "In12.Cu" signal "GND5")
		(28 "In13.Cu" signal "IN5")
		(30 "In14.Cu" signal "GND6")
		(32 "In15.Cu" signal "IN6")
		(34 "In16.Cu" signal "GND7")
		(2 "B.Cu" signal "BOTTOM")
		(9 "F.Adhes" user "F.Adhesive")
		(11 "B.Adhes" user "B.Adhesive")
		(13 "F.Paste" user "Package Geometry/Pastemask Top")
		(15 "B.Paste" user "Package Geometry/Pastemask Bottom")
		(5 "F.SilkS" user "Ref Des/Silkscreen Top")
		(7 "B.SilkS" user "Ref Des/Silkscreen Bottom")
		(1 "F.Mask" user "Board Geometry/Soldermask Top")
		(3 "B.Mask" user "Board Geometry/Soldermask Bottom")
		(17 "Dwgs.User" user "User.Drawings")
		(19 "Cmts.User" user "User.Comments")
		(21 "Eco1.User" user "User.Eco1")
		(23 "Eco2.User" user "User.Eco2")
		(25 "Edge.Cuts" user "Board Geometry/Outline")
		(27 "Margin" user)
		(31 "F.CrtYd" user "Package Geometry/Place Bound Top")
		(29 "B.CrtYd" user "Package Geometry/Place Bound Bottom")
		(35 "F.Fab" user "Ref Des/Assembly Top")
		(33 "B.Fab" user "Ref Des/Assembly Bottom")
	)
	(footprint ""
		(layer "B.Cu")
		(at 236.676692 -422.849548 90)
		(property "Reference" "C67"
			(at 0 0 90)
			(layer "B.SilkS")
			(hide yes)
			(effects
				(font
					(size 1.27 1.27)
				)
				(justify mirror)
			)
		)
		(property "Value" ""
			(at 0 0 90)
			(layer "B.Fab")
			(effects
				(font
					(size 1.27 1.27)
				)
				(justify mirror)
			)
		)
		(duplicate_pad_numbers_are_jumpers no)
		(fp_line
			(start 0.7874 -0.4064)
			(end -0.7874 -0.4064)
			(stroke
				(width 0.1524)
				(type default)
			)
			(layer "B.SilkS")
		)
		(fp_line
			(start -0.7874 -0.4064)
			(end -0.7874 0.4064)
			(stroke
				(width 0.1524)
				(type default)
			)
			(layer "B.SilkS")
		)
		(fp_line
			(start 0.7874 0.4064)
			(end 0.7874 -0.4064)
			(stroke
				(width 0.1524)
				(type default)
			)
			(layer "B.SilkS")
		)
		(fp_line
			(start -0.7874 0.4064)
			(end 0.7874 0.4064)
			(stroke
				(width 0.1524)
				(type default)
			)
			(layer "B.SilkS")
		)
		(fp_line
			(start 0.67945 -0.305054)
			(end 0.12065 -0.305054)
			(stroke
				(width 0.1)
				(type default)
			)
			(layer "B.Fab")
		)
		(fp_line
			(start 0.12065 -0.305054)
			(end 0.12065 -0.2794)
			(stroke
				(width 0.1)
				(type default)
			)
			(layer "B.Fab")
		)
		(fp_line
			(start -0.12065 -0.3048)
			(end -0.67945 -0.3048)
			(stroke
				(width 0.1)
				(type default)
			)
			(layer "B.Fab")
		)
		(fp_line
			(start -0.67945 -0.3048)
			(end -0.67945 0.3048)
			(stroke
				(width 0.1)
				(type default)
			)
			(layer "B.Fab")
		)
		(fp_line
			(start 0.12065 -0.2794)
			(end -0.12065 -0.2794)
			(stroke
				(width 0.1)
				(type default)
			)
			(layer "B.Fab")
		)
		(fp_line
			(start -0.12065 -0.2794)
			(end -0.12065 -0.3048)
			(stroke
				(width 0.1)
				(type default)
			)
			(layer "B.Fab")
		)
		(fp_line
			(start 0.12065 0.2794)
			(end 0.12065 0.3048)
			(stroke
				(width 0.1)
				(type default)
			)
			(layer "B.Fab")
		)
		(fp_line
			(start -0.120396 0.2794)
			(end 0.12065 0.2794)
			(stroke
				(width 0.1)
				(type default)
			)
			(layer "B.Fab")
		)
		(fp_line
			(start 0.67945 0.3048)
			(end 0.67945 -0.305054)
			(stroke
				(width 0.1)
				(type default)
			)
			(layer "B.Fab")
		)
		(fp_line
			(start 0.12065 0.3048)
			(end 0.67945 0.3048)
			(stroke
				(width 0.1)
				(type default)
			)
			(layer "B.Fab")
		)
		(fp_line
			(start -0.120396 0.3048)
			(end -0.120396 0.2794)
			(stroke
				(width 0.1)
				(type default)
			)
			(layer "B.Fab")
		)
		(fp_line
			(start -0.67945 0.3048)
			(end -0.120396 0.3048)
			(stroke
				(width 0.1)
				(type default)
			)
			(layer "B.Fab")
		)
		(pad "1" smd circle
			(at 0.40005 0 270)
			(size 0 0)
			(layers "B.Cu" "B.Mask" "B.Paste")
			(net "FM_GPU_HSC_EN_BUF_R1")
		)
		(pad "2" smd circle
			(at -0.40005 0 270)
			(size 0 0)
			(layers "B.Cu" "B.Mask" "B.Paste")
			(net "GND")
		)
	)
	(footprint ""
		(layer "B.Cu")
		(at 163.387532 -434.15458 -90)
		(property "Reference" "R4121"
			(at 0 0 90)
			(layer "B.SilkS")
			(hide yes)
			(effects
				(font
					(size 1.27 1.27)
				)
				(justify mirror)
			)
		)
		(property "Value" ""
			(at 0 0 90)
			(layer "B.Fab")
			(effects
				(font
					(size 1.27 1.27)
				)
				(justify mirror)
			)
		)
		(duplicate_pad_numbers_are_jumpers no)
		(fp_line
			(start -0.7874 0.4064)
			(end 0.7874 0.4064)
			(stroke
				(width 0.1524)
				(type default)
			)
			(layer "B.SilkS")
		)
		(fp_line
			(start 0.7874 0.4064)
			(end 0.7874 -0.4064)
			(stroke
				(width 0.1524)
				(type default)
			)
			(layer "B.SilkS")
		)
		(fp_line
			(start -0.7874 -0.4064)
			(end -0.7874 0.4064)
			(stroke
				(width 0.1524)
				(type default)
			)
			(layer "B.SilkS")
		)
		(fp_line
			(start 0.7874 -0.4064)
			(end -0.7874 -0.4064)
			(stroke
				(width 0.1524)
				(type default)
			)
			(layer "B.SilkS")
		)
		(fp_line
			(start -0.67945 0.3048)
			(end -0.120396 0.3048)
			(stroke
				(width 0.1)
				(type default)
			)
			(layer "B.Fab")
		)
		(fp_line
			(start -0.120396 0.3048)
			(end -0.120396 0.2794)
			(stroke
				(width 0.1)
				(type default)
			)
			(layer "B.Fab")
		)
		(fp_line
			(start 0.12065 0.3048)
			(end 0.67945 0.3048)
			(stroke
				(width 0.1)
				(type default)
			)
			(layer "B.Fab")
		)
		(fp_line
			(start 0.67945 0.3048)
			(end 0.67945 -0.305054)
			(stroke
				(width 0.1)
				(type default)
			)
			(layer "B.Fab")
		)
		(fp_line
			(start -0.120396 0.2794)
			(end 0.12065 0.2794)
			(stroke
				(width 0.1)
				(type default)
			)
			(layer "B.Fab")
		)
		(fp_line
			(start 0.12065 0.2794)
			(end 0.12065 0.3048)
			(stroke
				(width 0.1)
				(type default)
			)
			(layer "B.Fab")
		)
		(fp_line
			(start -0.12065 -0.2794)
			(end -0.12065 -0.3048)
			(stroke
				(width 0.1)
				(type default)
			)
			(layer "B.Fab")
		)
		(fp_line
			(start 0.12065 -0.2794)
			(end -0.12065 -0.2794)
			(stroke
				(width 0.1)
				(type default)
			)
			(layer "B.Fab")
		)
		(fp_line
			(start -0.67945 -0.3048)
			(end -0.67945 0.3048)
			(stroke
				(width 0.1)
				(type default)
			)
			(layer "B.Fab")
		)
		(fp_line
			(start -0.12065 -0.3048)
			(end -0.67945 -0.3048)
			(stroke
				(width 0.1)
				(type default)
			)
			(layer "B.Fab")
		)
		(fp_line
			(start 0.12065 -0.305054)
			(end 0.12065 -0.2794)
			(stroke
				(width 0.1)
				(type default)
			)
			(layer "B.Fab")
		)
		(fp_line
			(start 0.67945 -0.305054)
			(end 0.12065 -0.305054)
			(stroke
				(width 0.1)
				(type default)
			)
			(layer "B.Fab")
		)
		(pad "1" smd circle
			(at 0.40005 0 90)
			(size 0 0)
			(layers "B.Cu" "B.Mask" "B.Paste")
			(net "P3V3_AUX")
		)
		(pad "2" smd circle
			(at -0.40005 0 90)
			(size 0 0)
			(layers "B.Cu" "B.Mask" "B.Paste")
			(net "PRSNT_CABLE_GPU_B3_N")
		)
	)
)
